FILE_TYPE = CONNECTIVITY;
{Allegro Design Entry HDL 17.2-2016 S081 (4005846) 1/11/2022}
"PAGE_NUMBER" = 246;
0"NC";
1"P12V_AUX\g";
2"P3V3\g";
3"P5V\g";
4"P5V\g";
5"P3V3\g";
6"P12V_AUX\g";
7"P3V3_AUX\g";
8"P3V3\g";
9"P12V_AUX\g";
10"P5V\g";
11"P5V_AUX\g";
12"P12V_AUX\g";
13"P3V3\g";
14"P5V\g";
15"GND\g";
16"GND\g";
17"GND\g";
18"GND\g";
19"GND\g";
20"GND\g";
21"GND\g";
22"GND\g";
23"GND\g";
24"GND\g";
25"GND\g";
26"GND\g";
27"GND\g";
28"GND\g";
29"GND\g";
30"GND\g";
31"GND\g";
32"GND\g";
33"VR_P5V_EN";
34"FM_PS_EN_PLD_R";
35"PWRGD_P3V3_R1";
36"PWRGD_P5V_ISO_R";
37"PWRGD_P5V_N";
38"PWRGD_P5V";
39"PWRGD_P5V_ISO";
40"PWRGD_P3V3";
41"VR_P5V_EN_N";
42"FM_P5V_EN";
43"VR_P5V_EN_D_R1";
44"VR_P5V_EN_D";
45"VR_P5V_EN_N";
46"VR_P5V_EN_D_R";
%"UNIVERSAL_GND"
"1","(-4075,3125)","0","logical_power","I1";
;
BOM_COST"VR_SYSTEM "
HDL_POWER"GND"
CDS_LIB"logical_power"
VOLTAGE"0";
"A"21;
%"Q_RES"
"1","(-6275,4925)","0","pure_quanta","I10";
;
PART_NUMBER"CS00002JB13"
MATERIAL"EMPTY"
VALUE"0"
WATTAGE"1/16W"
PACK_TYPE"0402LF"
TOLERANCE"5%"
$LOCATION"R1607"
BOM_COST"VR_SYSTEM "
CDS_LIB"pure_quanta"
CDS_LOCATION"R1607"
$SEC"1"
CDS_SEC"1";
"B"
$PN"2"33;
"A"
$PN"1"34;
%"UNIVERSAL_GND"
"1","(-2025,3300)","0","logical_power","I100";
;
BOM_COST"VR_SYSTEM "
HDL_POWER"GND"
VOLTAGE"0"
CDS_LIB"logical_power";
"A"19;
%"UNIVERSAL_POWER"
"1","(-2025,4550)","0","logical_power","I101";
;
HDL_POWER"P12V_AUX"
CDS_LIB"logical_power"
BOM_COST"VR_SYSTEM ";
"A"1;
%"Q_RES"
"2","(-2025,4275)","0","pure_quanta","I102";
;
PART_NUMBER"CS41002FB09"
PACK_TYPE"0402LF"
TOLERANCE"1%"
VALUE"100K"
WATTAGE"1/16W"
MATERIAL"CHIP"
$LOCATION"R4680"
CDS_LIB"pure_quanta"
BOM_COST"VR_SYSTEM "
REUSE_ID"1"
CDS_LOCATION"R4680"
$SEC"1"
CDS_SEC"1";
"A"
$PN"1"1;
"B"
$PN"2"37;
%"UNIVERSAL_GND"
"1","(-1200,3300)","0","logical_power","I103";
;
BOM_COST"VR_SYSTEM "
HDL_POWER"GND"
VOLTAGE"0"
CDS_LIB"logical_power";
"A"16;
%"Q_RES"
"2","(-1200,4400)","0","pure_quanta","I104";
;
PART_NUMBER"CS21002FB06"
VALUE"1K"
TOLERANCE"1%"
PACK_TYPE"0402LF"
MATERIAL"CHIP"
WATTAGE"1/16W"
$LOCATION"R4678"
REUSE_ID"3"
CDS_LIB"pure_quanta"
CDS_LOCATION"R4678"
$SEC"1"
CDS_SEC"1";
"A"
$PN"1"36;
"B"
$PN"2"39;
%"APX80929SAG7"
"1","(-6650,3200)","2","pure_quanta","I105";
;
PART_NUMBER"AL080929000"
VALUE"APX809-29SAG-7"
PART_TYPE"SMLF"
MATERIAL"IC"
$LOCATION"U330"
CDS_LMAN_SYM_OUTLINE"-225,200,225,-200"
NEEDS_NO_SIZE"TRUE"
CDS_LIB"pure_quanta"
CDS_LOCATION"U330"
$SEC"1"
CDS_SEC"1";
"GND"
$PN"1"15;
"RESET_L \B"
$PN"2"35;
"VCC"
$PN"3"5;
%"UNIVERSAL_GND"
"1","(-7200,2775)","0","logical_power","I106";
;
HDL_POWER"GND"
CDS_LIB"logical_power";
"A"29;
%"Q_CAP"
"1","(-7200,3000)","2","pure_quanta","I107";
;
PART_NUMBER"CH4104K1B00"
TOLERANCE"10%"
MATERIAL"X7R"
VOLTAGE"25V"
VALUE"0.1UF"
PACK_TYPE"0402"
$LOCATION"C2360"
CDS_LIB"pure_quanta"
CDS_LOCATION"C2360"
$SEC"1"
CDS_SEC"1";
"B"
$PN"2"29;
"A"
$PN"1"5;
%"UNIVERSAL_POWER"
"1","(-7200,3450)","0","logical_power","I108";
;
HDL_POWER"P3V3"
BOM_COST"VR_SYSTEM "
CDS_LIB"logical_power";
"A"5;
%"Q_RES"
"2","(-5875,2900)","0","pure_quanta","I109";
;
PART_NUMBER"CS41002FB09"
WATTAGE"1/16W"
MATERIAL"CHIP"
VALUE"100K"
TOLERANCE"1%"
PACK_TYPE"0402LF"
$LOCATION"R4681"
CDS_LIB"pure_quanta"
CDS_LOCATION"R4681"
$SEC"1"
CDS_SEC"1";
"A"
$PN"1"35;
"B"
$PN"2"31;
%"Q_CAP"
"1","(-5975,7550)","2","pure_quanta","I11";
;
PART_NUMBER"CH4106K1B01"
TOLERANCE"10%"
VALUE"100NF"
VOLTAGE"50V"
MATERIAL"X7R"
PACK_TYPE"C0402"
$LOCATION"C1042"
CDS_LIB"pure_quanta"
BOM_COST"VR_SYSTEM "
REUSE_ID"81"
CDS_LOCATION"C1042"
$SEC"1"
CDS_SEC"1";
"B"
$PN"2"26;
"A"
$PN"1"11;
%"UNIVERSAL_GND"
"1","(-5875,2525)","0","logical_power","I110";
;
VOLTAGE"0"
HDL_POWER"GND"
BOM_COST"VR_SYSTEM "
CDS_LIB"logical_power";
"A"31;
%"UNIVERSAL_POWER"
"1","(-2700,4300)","0","logical_power","I111";
;
HDL_POWER"P5V"
CDS_LIB"logical_power"
BOM_COST"VR_SYSTEM ";
"A"4;
%"Q_RES"
"2","(-2625,3525)","0","pure_quanta","I112";
;
PART_NUMBER"CS41002FB09"
TOLERANCE"1%"
WATTAGE"1/16W"
MATERIAL"CHIP"
PACK_TYPE"0402LF"
VALUE"100K"
$LOCATION"R4682"
CDS_LIB"pure_quanta"
CDS_LOCATION"R4682"
$SEC"1"
CDS_SEC"1";
"A"
$PN"1"38;
"B"
$PN"2"32;
%"UNIVERSAL_GND"
"1","(-2625,3150)","0","logical_power","I113";
;
CDS_LIB"logical_power"
BOM_COST"VR_SYSTEM "
HDL_POWER"GND"
VOLTAGE"0";
"A"32;
%"UNIVERSAL_POWER"
"1","(-5900,3675)","0","logical_power","I114";
;
HDL_POWER"P3V3"
CDS_LIB"logical_power"
BOM_COST"VR_SYSTEM ";
"A"2;
%"UNIVERSAL_GND"
"1","(-5975,7200)","0","logical_power","I12";
;
VOLTAGE"0"
CDS_LIB"logical_power"
HDL_POWER"GND"
BOM_COST"VR_SYSTEM ";
"A"26;
%"UNIVERSAL_GND"
"1","(-5775,4275)","0","logical_power","I13";
;
VOLTAGE"0"
HDL_POWER"GND"
BOM_COST"VR_SYSTEM "
CDS_LIB"logical_power";
"A"30;
%"Q_RES"
"2","(-5775,4650)","0","pure_quanta","I14";
;
PART_NUMBER"CS41002FB09"
WATTAGE"1/16W"
TOLERANCE"1%"
PACK_TYPE"0402LF"
VALUE"100K"
MATERIAL"CHIP"
$LOCATION"R1641"
CDS_LIB"pure_quanta"
CDS_LOCATION"R1641"
$SEC"1"
CDS_SEC"1";
"A"
$PN"1"33;
"B"
$PN"2"30;
%"UNIVERSAL_GND"
"1","(-5125,4500)","0","logical_power","I15";
;
CDS_LIB"logical_power"
BOM_COST"VR_SYSTEM "
HDL_POWER"GND"
VOLTAGE"0";
"A"22;
%"Q_RES"
"2","(-5125,5525)","0","pure_quanta","I17";
;
PART_NUMBER"CS41002FB09"
WATTAGE"1/16W"
PACK_TYPE"0402LF"
TOLERANCE"1%"
VALUE"100K"
MATERIAL"CHIP"
$LOCATION"R1643"
CDS_LIB"pure_quanta"
REUSE_ID"1"
BOM_COST"VR_SYSTEM "
CDS_LOCATION"R1643"
$SEC"1"
CDS_SEC"1";
"A"
$PN"1"9;
"B"
$PN"2"41;
%"UNIVERSAL_POWER"
"1","(-5125,5800)","0","logical_power","I18";
;
HDL_POWER"P12V_AUX"
CDS_LIB"logical_power"
BOM_COST"VR_SYSTEM ";
"A"9;
%"Q_CAP"
"1","(-4075,3375)","0","pure_quanta","I2";
;
PART_NUMBER"CH4106K1B01"
VOLTAGE"50V"
VALUE"100NF"
MATERIAL"X7R"
TOLERANCE"10%"
PACK_TYPE"C0402"
$LOCATION"C1172"
CDS_LIB"pure_quanta"
BOM_COST"VR_SYSTEM "
CDS_LOCATION"C1172"
$SEC"1"
CDS_SEC"1";
"B"
$PN"2"21;
"A"
$PN"1"3;
%"UNIVERSAL_GND"
"1","(-4350,4750)","0","logical_power","I20";
;
BOM_COST"VR_SYSTEM "
HDL_POWER"GND"
CDS_LIB"logical_power"
VOLTAGE"0";
"A"25;
%"Q_RES"
"1","(-5575,6600)","0","pure_quanta","I22";
;
PART_NUMBER"CS31002FB08"
WATTAGE"1/16W"
MATERIAL"CHIP"
PACK_TYPE"0402LF"
VALUE"10K"
TOLERANCE"1%"
$LOCATION"R1642"
CDS_LIB"pure_quanta"
BOM_COST"VR_SYSTEM "
REUSE_ID"3"
CDS_LOCATION"R1642"
$SEC"1"
CDS_SEC"1";
"B"
$PN"2"46;
"A"
$PN"1"12;
%"UNIVERSAL_POWER"
"1","(-5975,6900)","0","logical_power","I23";
;
HDL_POWER"P12V_AUX"
CDS_LIB"logical_power"
BOM_COST"VR_SYSTEM ";
"A"12;
%"Q_CAP"
"1","(-5650,7550)","2","pure_quanta","I24";
;
PART_NUMBER"CH6103KEA00"
VALUE"10UF"
PACK_TYPE"C0805"
MATERIAL"X6S"
TOLERANCE"10%"
VOLTAGE"16V"
$LOCATION"C1170"
CDS_LIB"pure_quanta"
BOM_COST"VR_SYSTEM "
REUSE_ID"6"
CDS_LOCATION"C1170"
$SEC"1"
CDS_SEC"1";
"B"
$PN"2"26;
"A"
$PN"1"11;
%"Q_CAP"
"1","(-5325,7550)","2","pure_quanta","I25";
;
PART_NUMBER"CH6103KEA00"
TOLERANCE"10%"
MATERIAL"EMPTY"
VALUE"10UF"
VOLTAGE"16V"
PACK_TYPE"C0805"
$LOCATION"C1171"
CDS_LIB"pure_quanta"
BOM_COST"VR_SYSTEM "
REUSE_ID"8"
CDS_LOCATION"C1171"
$SEC"1"
CDS_SEC"1";
"B"
$PN"2"26;
"A"
$PN"1"11;
%"P1V0_AUX"
"1","(-5151,7849)","0","logical_power","I26";
;
HDL_POWER"P5V_AUX"
CDS_LIB"logical_power"
BOM_COST"VR_SYSTEM ";
"A"11;
%"Q_RES"
"2","(-4350,6300)","0","pure_quanta","I27";
;
PART_NUMBER"CS21002FB06"
PACK_TYPE"0402LF"
MATERIAL"CHIP"
WATTAGE"1/16W"
TOLERANCE"1%"
VALUE"1K"
$LOCATION"R1654"
CDS_LIB"pure_quanta"
REUSE_ID"3"
BOM_COST"VR_SYSTEM "
CDS_LOCATION"R1654"
$SEC"1"
CDS_SEC"1";
"A"
$PN"1"46;
"B"
$PN"2"43;
%"UNIVERSAL_GND"
"1","(-3950,6025)","0","logical_power","I28";
;
VOLTAGE"0"
HDL_POWER"GND"
BOM_COST"VR_SYSTEM "
CDS_LIB"logical_power";
"A"27;
%"UNIVERSAL_POWER"
"1","(-4075,3950)","0","logical_power","I3";
;
HDL_POWER"P5V"
BOM_COST"VR_SYSTEM "
CDS_LIB"logical_power";
"A"3;
%"MOSFET_NCH_1D3S"
"1","(-4000,6875)","7","pure_quanta","I30";
;
PART_NUMBER"BAMNR580000"
VALUE"PSMNR58-30YLH"
PART_TYPE"SMLF"
MATERIAL"IC"
LOCATION"Q57"
CDS_LIB"pure_quanta"
CDS_LMAN_SYM_OUTLINE"-150,200,150,-200"
NEEDS_NO_SIZE"TRUE"
$SEC"1"
CDS_SEC"1";
"1"
$PN"1"10;
"4"
$PN"4"46;
"2"
$PN"2"10;
"5"
$PN"5"11;
"3"
$PN"3"10;
%"UNIVERSAL_POWER"
"1","(-6625,2250)","0","logical_power","I31";
;
HDL_POWER"P3V3"
BOM_COST"VR_SYSTEM "
CDS_LIB"logical_power";
"A"13;
%"BAT547F"
"1","(-6175,1975)","0","pure_quanta","I32";
;
PART_NUMBER"BC0BAT54Z53"
PART_TYPE"SMLF"
VALUE"BAT547F"
MATERIAL"IC"
$LOCATION"D7"
CDS_LIB"pure_quanta"
CDS_LMAN_SYM_OUTLINE"-25,50,25,-50"
BOM_COST"VR_SYSTEM "
NEEDS_NO_SIZE"TRUE"
PIN_NAMES_ROTATE"TRUE"
CDS_LOCATION"D7"
$SEC"1"
CDS_SEC"1";
"3"
$PN"3"14;
"1"
$PN"1"13;
%"UNIVERSAL_POWER"
"1","(-5650,2250)","0","logical_power","I34";
;
HDL_POWER"P5V"
BOM_COST"VR_SYSTEM "
CDS_LIB"logical_power";
"A"14;
%"RT9818C44GV"
"1","(-3400,3625)","2","pure_quanta","I4";
;
PART_NUMBER"AL009818001"
MATERIAL"IC"
PART_TYPE"SMLF"
VALUE"RT9818C-44GV"
$LOCATION"U99"
CDS_LIB"pure_quanta"
CDS_LMAN_SYM_OUTLINE"-225,200,225,-200"
BOM_COST"VR_SYSTEM "
PIN_NAMES_ROTATE"TRUE"
CDS_LOCATION"U99"
$SEC"1"
CDS_SEC"1";
"GND"
$PN"2"18;
"RESET# \B"
$PN"1"38;
"VDD"
$PN"3"3;
%"UNIVERSAL_POWER"
"1","(-3475,7875)","0","logical_power","I42";
;
HDL_POWER"P5V"
CDS_LIB"logical_power"
BOM_COST"VR_SYSTEM ";
"A"10;
%"UNIVERSAL_GND"
"1","(-3375,7075)","0","logical_power","I43";
;
VOLTAGE"0"
CDS_LIB"logical_power"
HDL_POWER"GND"
BOM_COST"VR_SYSTEM ";
"A"24;
%"Q_CAP"
"1","(-3375,7400)","0","pure_quanta","I44";
;
PART_NUMBER"CH4106K1B01"
VALUE"100NF"
VOLTAGE"50V"
TOLERANCE"10%"
MATERIAL"X7R"
PACK_TYPE"C0402"
$LOCATION"C1227"
CDS_LIB"pure_quanta"
BOM_COST"VR_SYSTEM "
REUSE_ID"81"
CDS_LOCATION"C1227"
$SEC"1"
CDS_SEC"1";
"B"
$PN"2"24;
"A"
$PN"1"10;
%"Q_CAP"
"1","(-3050,7400)","0","pure_quanta","I45";
;
PART_NUMBER"CH6103KEA00"
TOLERANCE"10%"
MATERIAL"X6S"
VOLTAGE"16V"
VALUE"10UF"
PACK_TYPE"C0805"
$LOCATION"C1331"
CDS_LIB"pure_quanta"
REUSE_ID"6"
BOM_COST"VR_SYSTEM "
CDS_LOCATION"C1331"
$SEC"1"
CDS_SEC"1";
"B"
$PN"2"24;
"A"
$PN"1"10;
%"UNIVERSAL_GND"
"1","(-1150,5225)","0","logical_power","I47";
;
VOLTAGE"0"
CDS_LIB"logical_power"
HDL_POWER"GND"
BOM_COST"VR_SYSTEM ";
"A"17;
%"Q_CAP"
"1","(-1150,5550)","2","pure_quanta","I48";
;
PART_NUMBER"CH4106K1B01"
PACK_TYPE"C0402"
VALUE"100NF"
VOLTAGE"50V"
TOLERANCE"10%"
MATERIAL"X7R"
$LOCATION"C1332"
CDS_LIB"pure_quanta"
BOM_COST"VR_SYSTEM "
CDS_LOCATION"C1332"
$SEC"1"
CDS_SEC"1";
"B"
$PN"2"17;
"A"
$PN"1"7;
%"Q_CAP"
"1","(-825,5550)","2","pure_quanta","I49";
;
PART_NUMBER"CH6103KEA00"
PACK_TYPE"C0805"
TOLERANCE"10%"
VOLTAGE"16V"
VALUE"10UF"
MATERIAL"X6S"
$LOCATION"C1333"
CDS_LIB"pure_quanta"
BOM_COST"VR_SYSTEM "
CDS_LOCATION"C1333"
$SEC"1"
CDS_SEC"1";
"B"
$PN"2"17;
"A"
$PN"1"7;
%"UNIVERSAL_GND"
"1","(-2800,3350)","0","logical_power","I5";
;
BOM_COST"VR_SYSTEM "
HDL_POWER"GND"
CDS_LIB"logical_power"
VOLTAGE"0";
"A"18;
%"Q_CAP"
"1","(-425,5550)","2","pure_quanta","I50";
;
PART_NUMBER"CH6103KEA00"
VOLTAGE"16V"
VALUE"10UF"
MATERIAL"EMPTY"
PACK_TYPE"C0805"
TOLERANCE"10%"
$LOCATION"C1338"
CDS_LIB"pure_quanta"
BOM_COST"VR_SYSTEM "
CDS_LOCATION"C1338"
$SEC"1"
CDS_SEC"1";
"B"
$PN"2"17;
"A"
$PN"1"7;
%"MOSFET_NCH_1D3S"
"1","(125,4625)","7","pure_quanta","I51";
;
PART_NUMBER"BAMNR580000"
PART_TYPE"SMLF"
MATERIAL"IC"
VALUE"PSMNR58-30YLH"
LOCATION"Q56"
CDS_LIB"pure_quanta"
CDS_LMAN_SYM_OUTLINE"-150,200,150,-200"
NEEDS_NO_SIZE"TRUE"
$SEC"1"
CDS_SEC"1";
"1"
$PN"1"8;
"4"
$PN"4"36;
"2"
$PN"2"8;
"5"
$PN"5"7;
"3"
$PN"3"8;
%"P1V0_AUX"
"1","(-251,5949)","0","logical_power","I53";
;
HDL_POWER"P3V3_AUX"
BOM_COST"VR_SYSTEM "
CDS_LIB"logical_power";
"A"7;
%"Q_CAP"
"1","(775,5125)","0","pure_quanta","I58";
;
PART_NUMBER"CH4106K1B01"
PACK_TYPE"C0402"
MATERIAL"X7R"
VALUE"100NF"
VOLTAGE"50V"
TOLERANCE"10%"
$LOCATION"C1339"
BOM_COST"VR_SYSTEM "
CDS_LIB"pure_quanta"
CDS_LOCATION"C1339"
$SEC"1"
CDS_SEC"1";
"B"
$PN"2"20;
"A"
$PN"1"8;
%"UNIVERSAL_POWER"
"1","(675,5525)","0","logical_power","I59";
;
HDL_POWER"P3V3"
CDS_LIB"logical_power"
BOM_COST"VR_SYSTEM ";
"A"8;
%"Q_RES"
"2","(-1200,4800)","0","pure_quanta","I6";
;
PART_NUMBER"CS31002FB08"
TOLERANCE"1%"
VALUE"10K"
PACK_TYPE"0402LF"
WATTAGE"1/16W"
MATERIAL"CHIP"
$LOCATION"R1655"
CDS_LIB"pure_quanta"
CDS_LOCATION"R1655"
$SEC"1"
CDS_SEC"1";
"A"
$PN"1"6;
"B"
$PN"2"36;
%"UNIVERSAL_GND"
"1","(1150,4775)","0","logical_power","I60";
;
VOLTAGE"0"
CDS_LIB"logical_power"
HDL_POWER"GND"
BOM_COST"VR_SYSTEM ";
"A"20;
%"Q_CAP"
"1","(1150,5125)","0","pure_quanta","I61";
;
PART_NUMBER"CH6103KEA00"
MATERIAL"X6S"
PACK_TYPE"C0805"
TOLERANCE"10%"
VOLTAGE"16V"
VALUE"10UF"
$LOCATION"C1340"
BOM_COST"VR_SYSTEM "
CDS_LIB"pure_quanta"
CDS_LOCATION"C1340"
$SEC"1"
CDS_SEC"1";
"B"
$PN"2"20;
"A"
$PN"1"8;
%"UNIVERSAL_GND"
"1","(-2350,6225)","0","logical_power","I65";
;
CDS_LIB"logical_power"
VOLTAGE"0"
HDL_POWER"GND"
BOM_COST"VR_SYSTEM ";
"A"23;
%"MOSFET_NCH_GDS_ESD_PROTECTED"
"1","(-2375,6600)","0","pure_quanta","I67";
;
PART_NUMBER"BAM70020002"
VALUE"2N7002K"
MATERIAL"IC"
PART_TYPE"SMLF"
LOCATION"U324"
NEEDS_NO_SIZE"TRUE"
CDS_LMAN_SYM_OUTLINE"-125,150,125,-150"
CDS_LIB"pure_quanta"
$SEC"1"
CDS_SEC"1";
"S"
$PN"S"23;
"G"
$PN"G"45;
"D"
$PN"D"44;
%"Q_CAP"
"1","(-3950,6300)","0","pure_quanta","I68";
;
PART_NUMBER"CH4224K1B01"
MATERIAL"X7R"
TOLERANCE"10%"
PACK_TYPE"C0402"
VALUE"0.22UF"
VOLTAGE"25V"
LOCATION"C1226"
CDS_LIB"pure_quanta"
$SEC"1"
CDS_SEC"1";
"B"
$PN"2"27;
"A"
$PN"1"46;
%"MOSFET_NCH_DUAL"
"1","(-5175,4975)","0","pure_quanta","I69";
;
PART_NUMBER"BAM138K0003"
PART_TYPE"SMLF"
MATERIAL"IC"
VALUE"PJT138K"
LOCATION"Q37"
CDS_LIB"pure_quanta"
CDS_LMAN_SYM_OUTLINE"-150,150,150,-150"
SEC_TYPE""
NEEDS_NO_SIZE"TRUE"
SEC"1";
"D1"
$PN"6"41;
"G1"
$PN"2"33;
"S1"
$PN"1"22;
%"MOSFET_NCH_DUAL"
"2","(-4400,5300)","0","pure_quanta","I76";
;
PART_NUMBER"BAM138K0003"
MATERIAL"IC"
VALUE"PJT138K"
PART_TYPE"SMLF"
LOCATION"Q37"
CDS_LIB"pure_quanta"
CDS_LMAN_SYM_OUTLINE"-150,150,150,-150"
NEEDS_NO_SIZE"TRUE"
$SEC"2"
CDS_SEC"2";
"S2"
$PN"4"25;
"G2"
$PN"5"41;
"D2"
$PN"3"43;
%"Q_RES"
"2","(-2350,7225)","0","pure_quanta","I77";
;
PART_NUMBER"CS12436F201"
PACK_TYPE"1206LF"
VALUE"243"
TOLERANCE"1%"
WATTAGE"1/4W"
MATERIAL"CHIP"
LOCATION"R4638"
CDS_LIB"pure_quanta"
$SEC"1"
CDS_SEC"1";
"A"
$PN"1"10;
"B"
$PN"2"44;
%"Q_RES"
"2","(-1800,7225)","0","pure_quanta","I78";
;
PART_NUMBER"CS12436F201"
PACK_TYPE"1206LF"
MATERIAL"CHIP"
VALUE"243"
TOLERANCE"1%"
WATTAGE"1/4W"
LOCATION"R4639"
CDS_LIB"pure_quanta"
$SEC"1"
CDS_SEC"1";
"A"
$PN"1"10;
"B"
$PN"2"44;
%"Q_RES"
"2","(-1275,7225)","0","pure_quanta","I79";
;
PART_NUMBER"CS12436F201"
TOLERANCE"1%"
VALUE"243"
WATTAGE"1/4W"
MATERIAL"CHIP"
PACK_TYPE"1206LF"
LOCATION"R4640"
CDS_LIB"pure_quanta"
$SEC"1"
CDS_SEC"1";
"A"
$PN"1"10;
"B"
$PN"2"44;
%"Q_RES"
"2","(-750,7225)","0","pure_quanta","I80";
;
PART_NUMBER"CS12436F201"
TOLERANCE"1%"
VALUE"243"
WATTAGE"1/4W"
MATERIAL"CHIP"
PACK_TYPE"1206LF"
LOCATION"R4641"
CDS_LIB"pure_quanta"
$SEC"1"
CDS_SEC"1";
"A"
$PN"1"10;
"B"
$PN"2"44;
%"UNIVERSAL_GND"
"1","(-6075,3200)","0","logical_power","I87";
;
VOLTAGE"0"
HDL_POWER"GND"
BOM_COST"VR_SYSTEM "
CDS_LIB"logical_power";
"A"15;
%"Q_RES"
"2","(-5900,3350)","0","pure_quanta","I89";
;
PART_NUMBER"CS31002FB08"
TOLERANCE"1%"
WATTAGE"1/16W"
MATERIAL"EMPTY"
VALUE"10K"
PACK_TYPE"0402LF"
$LOCATION"R1706"
CDS_LIB"pure_quanta"
CDS_LOCATION"R1706"
$SEC"1"
CDS_SEC"1";
"A"
$PN"1"2;
"B"
$PN"2"35;
%"Q_RES"
"1","(-6275,4700)","0","pure_quanta","I9";
;
PART_NUMBER"CS00002JB13"
PACK_TYPE"0402LF"
MATERIAL"CHIP"
VALUE"0"
WATTAGE"1/16W"
TOLERANCE"5%"
$LOCATION"R1640"
BOM_COST"VR_SYSTEM "
CDS_LIB"pure_quanta"
CDS_LOCATION"R1640"
$SEC"1"
CDS_SEC"1";
"B"
$PN"2"33;
"A"
$PN"1"42;
%"Q_RES"
"1","(-5325,3100)","0","pure_quanta","I91";
;
PART_NUMBER"CS03322FB03"
MATERIAL"CHIP"
VALUE"33.2"
PACK_TYPE"0402LF"
$LOCATION"R4677"
CDS_LIB"pure_quanta"
WATTAGE"1/16W"
TOLERANCE"1%"
CDS_LOCATION"R4677"
$SEC"1"
CDS_SEC"1";
"B"
$PN"2"40;
"A"
$PN"1"35;
%"UNIVERSAL_POWER"
"1","(-1200,5075)","0","logical_power","I93";
;
HDL_POWER"P12V_AUX"
CDS_LIB"logical_power"
BOM_COST"VR_SYSTEM ";
"A"6;
%"Q_CAP"
"1","(175,4075)","0","pure_quanta","I94";
;
PART_NUMBER"CH4224K1B01"
VALUE"0.22UF"
VOLTAGE"25V"
TOLERANCE"10%"
MATERIAL"X7R"
PACK_TYPE"C0402"
$LOCATION"C2359"
CDS_LIB"pure_quanta"
CDS_LOCATION"C2359"
$SEC"1"
CDS_SEC"1";
"B"
$PN"2"28;
"A"
$PN"1"36;
%"UNIVERSAL_GND"
"1","(175,3800)","0","logical_power","I95";
;
VOLTAGE"0"
HDL_POWER"GND"
BOM_COST"VR_SYSTEM "
CDS_LIB"logical_power";
"A"28;
%"Q_RES"
"2","(-2700,3975)","0","pure_quanta","I96";
;
PART_NUMBER"CS31002FB08"
PACK_TYPE"0402LF"
VALUE"10K"
TOLERANCE"1%"
WATTAGE"1/16W"
MATERIAL"CHIP"
$LOCATION"R4679"
CDS_LIB"pure_quanta"
CDS_LOCATION"R4679"
$SEC"1"
CDS_SEC"1";
"A"
$PN"1"4;
"B"
$PN"2"38;
%"MOSFET_NCH_DUAL"
"2","(-1250,3750)","0","pure_quanta","I98";
;
PART_NUMBER"BAM138K0003"
MATERIAL"IC"
PART_TYPE"SMLF"
VALUE"PJT138K"
LOCATION"Q236"
CDS_LIB"pure_quanta"
CDS_LMAN_SYM_OUTLINE"-150,150,150,-150"
NEEDS_NO_SIZE"TRUE"
$SEC"2"
CDS_SEC"2";
"S2"
$PN"4"16;
"G2"
$PN"5"37;
"D2"
$PN"3"39;
%"MOSFET_NCH_DUAL"
"1","(-2075,3775)","0","pure_quanta","I99";
;
PART_NUMBER"BAM138K0003"
MATERIAL"IC"
VALUE"PJT138K"
PART_TYPE"SMLF"
LOCATION"Q236"
NEEDS_NO_SIZE"TRUE"
CDS_LMAN_SYM_OUTLINE"-150,150,150,-150"
CDS_LIB"pure_quanta"
$SEC"1"
CDS_SEC"1";
"D1"
$PN"6"37;
"G1"
$PN"2"38;
"S1"
$PN"1"19;
END.
